(kicad_pcb
	(version 20260206)
	(generator "pcbnew")
	(generator_version "10.0")
	(general
		(thickness 1.6)
		(legacy_teardrops no)
	)
	(paper "A4")
	(title_block
		(title "panther-plus-userver — 13130-1b_20150205.brd")
		(comment 1 "Honey Badger (Wiwynn) / footprint 894 of 1509 (DIMM1), pads 79-85 of 210")
	)
	(layers
		(0 "F.Cu" signal "TOP")
		(4 "In1.Cu" signal "L2")
		(6 "In2.Cu" signal "L3")
		(8 "In3.Cu" signal "L4")
		(10 "In4.Cu" signal "L5")
		(12 "In5.Cu" signal "L6")
		(14 "In6.Cu" signal "L7")
		(16 "In7.Cu" signal "L8")
		(18 "In8.Cu" signal "L9")
		(20 "In9.Cu" signal "L10")
		(22 "In10.Cu" signal "L11")
		(2 "B.Cu" signal "BOTTOM")
		(9 "F.Adhes" user "F.Adhesive")
		(11 "B.Adhes" user "B.Adhesive")
		(13 "F.Paste" user "Package Geometry/Pastemask Top")
		(15 "B.Paste" user "Package Geometry/Pastemask Bottom")
		(5 "F.SilkS" user "Ref Des/Silkscreen Top")
		(7 "B.SilkS" user "Ref Des/Silkscreen Bottom")
		(1 "F.Mask" user "Board Geometry/Soldermask Top")
		(3 "B.Mask" user "Board Geometry/Soldermask Bottom")
		(17 "Dwgs.User" user "User.Drawings")
		(19 "Cmts.User" user "User.Comments")
		(21 "Eco1.User" user "User.Eco1")
		(23 "Eco2.User" user "User.Eco2")
		(25 "Edge.Cuts" user "Board Geometry/Outline")
		(27 "Margin" user)
		(31 "F.CrtYd" user "Package Geometry/Place Bound Top")
		(29 "B.CrtYd" user "Package Geometry/Place Bound Bottom")
		(35 "F.Fab" user "Ref Des/Assembly Top")
		(33 "B.Fab" user "Ref Des/Assembly Bottom")
	)
	(footprint ""
		(layer "B.Cu")
		(at 158.500064 -66.699892 180)
		(property "Reference" "DIMM1"
			(at 0 0 0)
			(layer "B.SilkS")
			(hide yes)
			(effects
				(font
					(size 1.27 1.27)
				)
				(justify mirror)
			)
		)
		(property "Value" "DDR3-204P-142-COLAY-1-GP-U"
			(at 41.312338 -16.676878 180)
			(unlocked yes)
			(layer "B.Fab")
			(hide yes)
			(effects
				(font
					(size 1.016 1.016)
					(thickness 0.1524)
				)
				(justify mirror)
			)
		)
		(property "Device Type" "AS0A626-J8R6-7H-COLAY-1"
			(at 41.312338 -18.200878 180)
			(unlocked yes)
			(layer "B.Fab")
			(hide yes)
			(effects
				(font
					(size 1.016 1.016)
					(thickness 0.1524)
				)
				(justify mirror)
			)
		)
		(duplicate_pad_numbers_are_jumpers no)
		(pad "77" smd custom
			(at -6.450076 -4.100068)
			(size 0.1143 0.1143)
			(layers "B.Cu" "B.Mask" "B.Paste")
			(net "M_A_DQS_DP8")
			(options
				(clearance outline)
				(anchor circle)
			)
			(primitives
				(gr_poly
					(pts
						(xy 0 -0.9017) (xy -0.03175 -0.89916) (xy -0.0635 -0.889) (xy -0.09144 -0.87376) (xy -0.11684 -0.85344)
						(xy -0.13716 -0.82804) (xy -0.1524 -0.8001) (xy -0.16256 -0.76835) (xy -0.1651 -0.7366) (xy -0.1651 -0.44958)
						(xy -0.17272 -0.44196) (xy -0.19812 -0.4064) (xy -0.2032 -0.39624) (xy -0.20701 -0.38735) (xy -0.21209 -0.37719)
						(xy -0.2159 -0.36703) (xy -0.21844 -0.35687) (xy -0.22225 -0.34544) (xy -0.22352 -0.33528) (xy -0.22606 -0.32512)
						(xy -0.22733 -0.31369) (xy -0.22733 -0.30353) (xy -0.2286 -0.2921) (xy -0.22733 -0.28067) (xy -0.22733 -0.27051)
						(xy -0.22606 -0.25908) (xy -0.22352 -0.24892) (xy -0.22225 -0.23876) (xy -0.21844 -0.22733) (xy -0.2159 -0.21717)
						(xy -0.21209 -0.20701) (xy -0.20701 -0.19685) (xy -0.2032 -0.18796) (xy -0.19812 -0.1778) (xy -0.17272 -0.14224)
						(xy -0.1651 -0.13462) (xy -0.1651 0.7366) (xy -0.16256 0.76835) (xy -0.1524 0.8001) (xy -0.13716 0.82804)
						(xy -0.11684 0.85344) (xy -0.09144 0.87376) (xy -0.0635 0.889) (xy -0.03175 0.89916) (xy 0 0.9017)
						(xy 0.03175 0.89916) (xy 0.0635 0.889) (xy 0.09144 0.87376) (xy 0.11684 0.85344) (xy 0.13716 0.82804)
						(xy 0.1524 0.8001) (xy 0.16256 0.76835) (xy 0.1651 0.7366) (xy 0.1651 -0.13462) (xy 0.17272 -0.14224)
						(xy 0.19812 -0.1778) (xy 0.2032 -0.18796) (xy 0.20701 -0.19685) (xy 0.21209 -0.20701) (xy 0.2159 -0.21717)
						(xy 0.21844 -0.22733) (xy 0.22225 -0.23876) (xy 0.22352 -0.24892) (xy 0.22606 -0.25908) (xy 0.22733 -0.27051)
						(xy 0.22733 -0.28067) (xy 0.2286 -0.2921) (xy 0.22733 -0.30353) (xy 0.22733 -0.31369) (xy 0.22606 -0.32512)
						(xy 0.22352 -0.33528) (xy 0.22225 -0.34544) (xy 0.21844 -0.35687) (xy 0.2159 -0.36703) (xy 0.21209 -0.37719)
						(xy 0.20701 -0.38735) (xy 0.2032 -0.39624) (xy 0.19812 -0.4064) (xy 0.17272 -0.44196) (xy 0.1651 -0.44958)
						(xy 0.1651 -0.7366) (xy 0.16256 -0.76835) (xy 0.1524 -0.8001) (xy 0.13716 -0.82804) (xy 0.11684 -0.85344)
						(xy 0.09144 -0.87376) (xy 0.0635 -0.889) (xy 0.03175 -0.89916)
					)
					(width 0)
					(fill yes)
				)
			)
		)
		(pad "78" smd custom
			(at -6.150102 4.100068)
			(size 0.1143 0.1143)
			(layers "B.Cu" "B.Mask" "B.Paste")
			(net "GND")
			(options
				(clearance outline)
				(anchor circle)
			)
			(primitives
				(gr_poly
					(pts
						(xy 0 -0.9017) (xy -0.03175 -0.89916) (xy -0.0635 -0.889) (xy -0.09144 -0.87376) (xy -0.11684 -0.85344)
						(xy -0.13716 -0.82804) (xy -0.1524 -0.8001) (xy -0.16256 -0.76835) (xy -0.1651 -0.7366) (xy -0.1651 0.13462)
						(xy -0.17272 0.14224) (xy -0.19812 0.1778) (xy -0.2032 0.18796) (xy -0.20701 0.19685) (xy -0.21209 0.20701)
						(xy -0.2159 0.21717) (xy -0.21844 0.22733) (xy -0.22225 0.23876) (xy -0.22352 0.24892) (xy -0.22606 0.25908)
						(xy -0.22733 0.27051) (xy -0.22733 0.28067) (xy -0.2286 0.2921) (xy -0.22733 0.30353) (xy -0.22733 0.31369)
						(xy -0.22606 0.32512) (xy -0.22352 0.33528) (xy -0.22225 0.34544) (xy -0.21844 0.35687) (xy -0.2159 0.36703)
						(xy -0.21209 0.37719) (xy -0.20701 0.38735) (xy -0.2032 0.39624) (xy -0.19812 0.4064) (xy -0.17272 0.44196)
						(xy -0.1651 0.44958) (xy -0.1651 0.7366) (xy -0.16256 0.76835) (xy -0.1524 0.8001) (xy -0.13716 0.82804)
						(xy -0.11684 0.85344) (xy -0.09144 0.87376) (xy -0.0635 0.889) (xy -0.03175 0.89916) (xy 0 0.9017)
						(xy 0.03175 0.89916) (xy 0.0635 0.889) (xy 0.09144 0.87376) (xy 0.11684 0.85344) (xy 0.13716 0.82804)
						(xy 0.1524 0.8001) (xy 0.16256 0.76835) (xy 0.1651 0.7366) (xy 0.1651 0.44958) (xy 0.17272 0.44196)
						(xy 0.19812 0.4064) (xy 0.2032 0.39624) (xy 0.20701 0.38735) (xy 0.21209 0.37719) (xy 0.2159 0.36703)
						(xy 0.21844 0.35687) (xy 0.22225 0.34544) (xy 0.22352 0.33528) (xy 0.22606 0.32512) (xy 0.22733 0.31369)
						(xy 0.22733 0.30353) (xy 0.2286 0.2921) (xy 0.22733 0.28067) (xy 0.22733 0.27051) (xy 0.22606 0.25908)
						(xy 0.22352 0.24892) (xy 0.22225 0.23876) (xy 0.21844 0.22733) (xy 0.2159 0.21717) (xy 0.21209 0.20701)
						(xy 0.20701 0.19685) (xy 0.2032 0.18796) (xy 0.19812 0.1778) (xy 0.17272 0.14224) (xy 0.1651 0.13462)
						(xy 0.1651 -0.7366) (xy 0.16256 -0.76835) (xy 0.1524 -0.8001) (xy 0.13716 -0.82804) (xy 0.11684 -0.85344)
						(xy 0.09144 -0.87376) (xy 0.0635 -0.889) (xy 0.03175 -0.89916)
					)
					(width 0)
					(fill yes)
				)
			)
		)
		(pad "79" smd custom
			(at -5.849874 -4.100068)
			(size 0.1143 0.1143)
			(layers "B.Cu" "B.Mask" "B.Paste")
			(net "GND")
			(options
				(clearance outline)
				(anchor circle)
			)
			(primitives
				(gr_poly
					(pts
						(xy 0 -0.9017) (xy -0.03175 -0.89916) (xy -0.0635 -0.889) (xy -0.09144 -0.87376) (xy -0.11684 -0.85344)
						(xy -0.13716 -0.82804) (xy -0.1524 -0.8001) (xy -0.16256 -0.76835) (xy -0.1651 -0.7366) (xy -0.1651 -0.19685)
						(xy -0.17272 -0.18923) (xy -0.17907 -0.18034) (xy -0.18669 -0.17145) (xy -0.19177 -0.16256) (xy -0.19812 -0.15367)
						(xy -0.20828 -0.13335) (xy -0.21971 -0.10287) (xy -0.22225 -0.09271) (xy -0.22479 -0.08128) (xy -0.22606 -0.07112)
						(xy -0.2286 -0.05969) (xy -0.2286 -0.01651) (xy -0.22606 -0.00508) (xy -0.22479 0.00508) (xy -0.22225 0.01651)
						(xy -0.21971 0.02667) (xy -0.20828 0.05715) (xy -0.19812 0.07747) (xy -0.19177 0.08636) (xy -0.18669 0.09525)
						(xy -0.17907 0.10414) (xy -0.17272 0.11303) (xy -0.1651 0.12065) (xy -0.1651 0.7366) (xy -0.16256 0.76835)
						(xy -0.1524 0.8001) (xy -0.13716 0.82804) (xy -0.11684 0.85344) (xy -0.09144 0.87376) (xy -0.0635 0.889)
						(xy -0.03175 0.89916) (xy 0 0.9017) (xy 0.03175 0.89916) (xy 0.0635 0.889) (xy 0.09144 0.87376)
						(xy 0.11684 0.85344) (xy 0.13716 0.82804) (xy 0.1524 0.8001) (xy 0.16256 0.76835) (xy 0.1651 0.7366)
						(xy 0.1651 0.11938) (xy 0.17272 0.11176) (xy 0.19812 0.0762) (xy 0.2032 0.06604) (xy 0.20701 0.05715)
						(xy 0.21209 0.04699) (xy 0.2159 0.03683) (xy 0.21844 0.02667) (xy 0.22225 0.01524) (xy 0.22352 0.00508)
						(xy 0.22606 -0.00508) (xy 0.22733 -0.01651) (xy 0.22733 -0.02667) (xy 0.2286 -0.0381) (xy 0.22733 -0.04953)
						(xy 0.22733 -0.05969) (xy 0.22606 -0.07112) (xy 0.22352 -0.08128) (xy 0.22225 -0.09144) (xy 0.21844 -0.10287)
						(xy 0.2159 -0.11303) (xy 0.21209 -0.12319) (xy 0.20701 -0.13335) (xy 0.2032 -0.14224) (xy 0.19812 -0.1524)
						(xy 0.17272 -0.18796) (xy 0.1651 -0.19558) (xy 0.1651 -0.7366) (xy 0.16256 -0.76835) (xy 0.1524 -0.8001)
						(xy 0.13716 -0.82804) (xy 0.11684 -0.85344) (xy 0.09144 -0.87376) (xy 0.0635 -0.889) (xy 0.03175 -0.89916)
					)
					(width 0)
					(fill yes)
				)
			)
		)
		(pad "80" smd custom
			(at -5.5499 4.100068)
			(size 0.1143 0.1143)
			(layers "B.Cu" "B.Mask" "B.Paste")
			(net "M_A_ECC6")
			(options
				(clearance outline)
				(anchor circle)
			)
			(primitives
				(gr_poly
					(pts
						(xy 0 -0.9017) (xy -0.03175 -0.89916) (xy -0.0635 -0.889) (xy -0.09144 -0.87376) (xy -0.11684 -0.85344)
						(xy -0.13716 -0.82804) (xy -0.1524 -0.8001) (xy -0.16256 -0.76835) (xy -0.1651 -0.7366) (xy -0.1651 -0.11938)
						(xy -0.17272 -0.11176) (xy -0.19812 -0.0762) (xy -0.2032 -0.06604) (xy -0.20701 -0.05715) (xy -0.21209 -0.04699)
						(xy -0.2159 -0.03683) (xy -0.21844 -0.02667) (xy -0.22225 -0.01524) (xy -0.22352 -0.00508) (xy -0.22606 0.00508)
						(xy -0.22733 0.01651) (xy -0.22733 0.02667) (xy -0.2286 0.0381) (xy -0.22733 0.04953) (xy -0.22733 0.05969)
						(xy -0.22606 0.07112) (xy -0.22352 0.08128) (xy -0.22225 0.09144) (xy -0.21844 0.10287) (xy -0.2159 0.11303)
						(xy -0.21209 0.12319) (xy -0.20701 0.13335) (xy -0.2032 0.14224) (xy -0.19812 0.1524) (xy -0.17272 0.18796)
						(xy -0.1651 0.19558) (xy -0.1651 0.7366) (xy -0.16256 0.76835) (xy -0.1524 0.8001) (xy -0.13716 0.82804)
						(xy -0.11684 0.85344) (xy -0.09144 0.87376) (xy -0.0635 0.889) (xy -0.03175 0.89916) (xy 0 0.9017)
						(xy 0.03175 0.89916) (xy 0.0635 0.889) (xy 0.09144 0.87376) (xy 0.11684 0.85344) (xy 0.13716 0.82804)
						(xy 0.1524 0.8001) (xy 0.16256 0.76835) (xy 0.1651 0.7366) (xy 0.1651 0.19685) (xy 0.17272 0.18923)
						(xy 0.17907 0.18034) (xy 0.18669 0.17145) (xy 0.19177 0.16256) (xy 0.19812 0.15367) (xy 0.20828 0.13335)
						(xy 0.21971 0.10287) (xy 0.22225 0.09271) (xy 0.22479 0.08128) (xy 0.22606 0.07112) (xy 0.2286 0.05969)
						(xy 0.2286 0.01651) (xy 0.22606 0.00508) (xy 0.22479 -0.00508) (xy 0.22225 -0.01651) (xy 0.21971 -0.02667)
						(xy 0.20828 -0.05715) (xy 0.19812 -0.07747) (xy 0.19177 -0.08636) (xy 0.18669 -0.09525) (xy 0.17907 -0.10414)
						(xy 0.17272 -0.11303) (xy 0.1651 -0.12065) (xy 0.1651 -0.7366) (xy 0.16256 -0.76835) (xy 0.1524 -0.8001)
						(xy 0.13716 -0.82804) (xy 0.11684 -0.85344) (xy 0.09144 -0.87376) (xy 0.0635 -0.889) (xy 0.03175 -0.89916)
					)
					(width 0)
					(fill yes)
				)
			)
		)
		(pad "81" smd custom
			(at -5.249926 -4.100068)
			(size 0.1143 0.1143)
			(layers "B.Cu" "B.Mask" "B.Paste")
			(net "M_A_ECC2")
			(options
				(clearance outline)
				(anchor circle)
			)
			(primitives
				(gr_poly
					(pts
						(xy 0 -0.9017) (xy -0.03175 -0.89916) (xy -0.0635 -0.889) (xy -0.09144 -0.87376) (xy -0.11684 -0.85344)
						(xy -0.13716 -0.82804) (xy -0.1524 -0.8001) (xy -0.16256 -0.76835) (xy -0.1651 -0.7366) (xy -0.1651 -0.44958)
						(xy -0.17272 -0.44196) (xy -0.19812 -0.4064) (xy -0.2032 -0.39624) (xy -0.20701 -0.38735) (xy -0.21209 -0.37719)
						(xy -0.2159 -0.36703) (xy -0.21844 -0.35687) (xy -0.22225 -0.34544) (xy -0.22352 -0.33528) (xy -0.22606 -0.32512)
						(xy -0.22733 -0.31369) (xy -0.22733 -0.30353) (xy -0.2286 -0.2921) (xy -0.22733 -0.28067) (xy -0.22733 -0.27051)
						(xy -0.22606 -0.25908) (xy -0.22352 -0.24892) (xy -0.22225 -0.23876) (xy -0.21844 -0.22733) (xy -0.2159 -0.21717)
						(xy -0.21209 -0.20701) (xy -0.20701 -0.19685) (xy -0.2032 -0.18796) (xy -0.19812 -0.1778) (xy -0.17272 -0.14224)
						(xy -0.1651 -0.13462) (xy -0.1651 0.7366) (xy -0.16256 0.76835) (xy -0.1524 0.8001) (xy -0.13716 0.82804)
						(xy -0.11684 0.85344) (xy -0.09144 0.87376) (xy -0.0635 0.889) (xy -0.03175 0.89916) (xy 0 0.9017)
						(xy 0.03175 0.89916) (xy 0.0635 0.889) (xy 0.09144 0.87376) (xy 0.11684 0.85344) (xy 0.13716 0.82804)
						(xy 0.1524 0.8001) (xy 0.16256 0.76835) (xy 0.1651 0.7366) (xy 0.1651 -0.13462) (xy 0.17272 -0.14224)
						(xy 0.19812 -0.1778) (xy 0.2032 -0.18796) (xy 0.20701 -0.19685) (xy 0.21209 -0.20701) (xy 0.2159 -0.21717)
						(xy 0.21844 -0.22733) (xy 0.22225 -0.23876) (xy 0.22352 -0.24892) (xy 0.22606 -0.25908) (xy 0.22733 -0.27051)
						(xy 0.22733 -0.28067) (xy 0.2286 -0.2921) (xy 0.22733 -0.30353) (xy 0.22733 -0.31369) (xy 0.22606 -0.32512)
						(xy 0.22352 -0.33528) (xy 0.22225 -0.34544) (xy 0.21844 -0.35687) (xy 0.2159 -0.36703) (xy 0.21209 -0.37719)
						(xy 0.20701 -0.38735) (xy 0.2032 -0.39624) (xy 0.19812 -0.4064) (xy 0.17272 -0.44196) (xy 0.1651 -0.44958)
						(xy 0.1651 -0.7366) (xy 0.16256 -0.76835) (xy 0.1524 -0.8001) (xy 0.13716 -0.82804) (xy 0.11684 -0.85344)
						(xy 0.09144 -0.87376) (xy 0.0635 -0.889) (xy 0.03175 -0.89916)
					)
					(width 0)
					(fill yes)
				)
			)
		)
		(pad "82" smd custom
			(at -4.949952 4.100068)
			(size 0.1143 0.1143)
			(layers "B.Cu" "B.Mask" "B.Paste")
			(net "M_A_ECC7")
			(options
				(clearance outline)
				(anchor circle)
			)
			(primitives
				(gr_poly
					(pts
						(xy 0 -0.9017) (xy -0.03175 -0.89916) (xy -0.0635 -0.889) (xy -0.09144 -0.87376) (xy -0.11684 -0.85344)
						(xy -0.13716 -0.82804) (xy -0.1524 -0.8001) (xy -0.16256 -0.76835) (xy -0.1651 -0.7366) (xy -0.1651 0.13462)
						(xy -0.17272 0.14224) (xy -0.19812 0.1778) (xy -0.2032 0.18796) (xy -0.20701 0.19685) (xy -0.21209 0.20701)
						(xy -0.2159 0.21717) (xy -0.21844 0.22733) (xy -0.22225 0.23876) (xy -0.22352 0.24892) (xy -0.22606 0.25908)
						(xy -0.22733 0.27051) (xy -0.22733 0.28067) (xy -0.2286 0.2921) (xy -0.22733 0.30353) (xy -0.22733 0.31369)
						(xy -0.22606 0.32512) (xy -0.22352 0.33528) (xy -0.22225 0.34544) (xy -0.21844 0.35687) (xy -0.2159 0.36703)
						(xy -0.21209 0.37719) (xy -0.20701 0.38735) (xy -0.2032 0.39624) (xy -0.19812 0.4064) (xy -0.17272 0.44196)
						(xy -0.1651 0.44958) (xy -0.1651 0.7366) (xy -0.16256 0.76835) (xy -0.1524 0.8001) (xy -0.13716 0.82804)
						(xy -0.11684 0.85344) (xy -0.09144 0.87376) (xy -0.0635 0.889) (xy -0.03175 0.89916) (xy 0 0.9017)
						(xy 0.03175 0.89916) (xy 0.0635 0.889) (xy 0.09144 0.87376) (xy 0.11684 0.85344) (xy 0.13716 0.82804)
						(xy 0.1524 0.8001) (xy 0.16256 0.76835) (xy 0.1651 0.7366) (xy 0.1651 0.44958) (xy 0.17272 0.44196)
						(xy 0.19812 0.4064) (xy 0.2032 0.39624) (xy 0.20701 0.38735) (xy 0.21209 0.37719) (xy 0.2159 0.36703)
						(xy 0.21844 0.35687) (xy 0.22225 0.34544) (xy 0.22352 0.33528) (xy 0.22606 0.32512) (xy 0.22733 0.31369)
						(xy 0.22733 0.30353) (xy 0.2286 0.2921) (xy 0.22733 0.28067) (xy 0.22733 0.27051) (xy 0.22606 0.25908)
						(xy 0.22352 0.24892) (xy 0.22225 0.23876) (xy 0.21844 0.22733) (xy 0.2159 0.21717) (xy 0.21209 0.20701)
						(xy 0.20701 0.19685) (xy 0.2032 0.18796) (xy 0.19812 0.1778) (xy 0.17272 0.14224) (xy 0.1651 0.13462)
						(xy 0.1651 -0.7366) (xy 0.16256 -0.76835) (xy 0.1524 -0.8001) (xy 0.13716 -0.82804) (xy 0.11684 -0.85344)
						(xy 0.09144 -0.87376) (xy 0.0635 -0.889) (xy 0.03175 -0.89916)
					)
					(width 0)
					(fill yes)
				)
			)
		)
		(pad "83" smd custom
			(at -4.649978 -4.100068)
			(size 0.1143 0.1143)
			(layers "B.Cu" "B.Mask" "B.Paste")
			(net "M_A_ECC3")
			(options
				(clearance outline)
				(anchor circle)
			)
			(primitives
				(gr_poly
					(pts
						(xy 0 -0.9017) (xy -0.03175 -0.89916) (xy -0.0635 -0.889) (xy -0.09144 -0.87376) (xy -0.11684 -0.85344)
						(xy -0.13716 -0.82804) (xy -0.1524 -0.8001) (xy -0.16256 -0.76835) (xy -0.1651 -0.7366) (xy -0.1651 -0.19685)
						(xy -0.17272 -0.18923) (xy -0.17907 -0.18034) (xy -0.18669 -0.17145) (xy -0.19177 -0.16256) (xy -0.19812 -0.15367)
						(xy -0.20828 -0.13335) (xy -0.21971 -0.10287) (xy -0.22225 -0.09271) (xy -0.22479 -0.08128) (xy -0.22606 -0.07112)
						(xy -0.2286 -0.05969) (xy -0.2286 -0.01651) (xy -0.22606 -0.00508) (xy -0.22479 0.00508) (xy -0.22225 0.01651)
						(xy -0.21971 0.02667) (xy -0.20828 0.05715) (xy -0.19812 0.07747) (xy -0.19177 0.08636) (xy -0.18669 0.09525)
						(xy -0.17907 0.10414) (xy -0.17272 0.11303) (xy -0.1651 0.12065) (xy -0.1651 0.7366) (xy -0.16256 0.76835)
						(xy -0.1524 0.8001) (xy -0.13716 0.82804) (xy -0.11684 0.85344) (xy -0.09144 0.87376) (xy -0.0635 0.889)
						(xy -0.03175 0.89916) (xy 0 0.9017) (xy 0.03175 0.89916) (xy 0.0635 0.889) (xy 0.09144 0.87376)
						(xy 0.11684 0.85344) (xy 0.13716 0.82804) (xy 0.1524 0.8001) (xy 0.16256 0.76835) (xy 0.1651 0.7366)
						(xy 0.1651 0.11938) (xy 0.17272 0.11176) (xy 0.19812 0.0762) (xy 0.2032 0.06604) (xy 0.20701 0.05715)
						(xy 0.21209 0.04699) (xy 0.2159 0.03683) (xy 0.21844 0.02667) (xy 0.22225 0.01524) (xy 0.22352 0.00508)
						(xy 0.22606 -0.00508) (xy 0.22733 -0.01651) (xy 0.22733 -0.02667) (xy 0.2286 -0.0381) (xy 0.22733 -0.04953)
						(xy 0.22733 -0.05969) (xy 0.22606 -0.07112) (xy 0.22352 -0.08128) (xy 0.22225 -0.09144) (xy 0.21844 -0.10287)
						(xy 0.2159 -0.11303) (xy 0.21209 -0.12319) (xy 0.20701 -0.13335) (xy 0.2032 -0.14224) (xy 0.19812 -0.1524)
						(xy 0.17272 -0.18796) (xy 0.1651 -0.19558) (xy 0.1651 -0.7366) (xy 0.16256 -0.76835) (xy 0.1524 -0.8001)
						(xy 0.13716 -0.82804) (xy 0.11684 -0.85344) (xy 0.09144 -0.87376) (xy 0.0635 -0.889) (xy 0.03175 -0.89916)
					)
					(width 0)
					(fill yes)
				)
			)
		)
	)
)
